# BASEBOARD_FAB2 (Tioga Pass) — schematic netlist excerpt (pin names and nets, part order shuffled) for the footprints in the layout excerpt that follows; sources: Cadence DE-HDL packaged netlist, KiCad conversion of Wiwynn_Tioga_Pass_MB.brd

C6D3  CAP_A  22.0UF 4V 20% X6S  pkg 0603V  page 42 : A = PVCCIO_CPU0 ; B = GND
R6F5  RES  49.9 1% CHIP  pkg 0402  page 89 : A = FM_ADR_COMPLETE_CPU1_N ; B = FM_ADR_COMPLETE_GHJ_N

(kicad_pcb
	(version 20260206)
	(generator "pcbnew")
	(generator_version "10.0")
	(general
		(thickness 1.6)
		(legacy_teardrops no)
	)
	(paper "A4")
	(title_block
		(title "Wiwynn_Tioga_Pass_MB.brd")
		(comment 1 "Tioga Pass / footprints 974-975 of 4770")
	)
	(layers
		(0 "F.Cu" signal "TOP")
		(4 "In1.Cu" signal "L2GND")
		(6 "In2.Cu" signal "L3")
		(8 "In3.Cu" signal "L4GND")
		(10 "In4.Cu" signal "L5")
		(12 "In5.Cu" signal "L6GND")
		(14 "In6.Cu" signal "L7VCC")
		(16 "In7.Cu" signal "L8VCC")
		(18 "In8.Cu" signal "L9GND")
		(20 "In9.Cu" signal "L10")
		(22 "In10.Cu" signal "L11GND")
		(24 "In11.Cu" signal "L12")
		(26 "In12.Cu" signal "L13GND")
		(2 "B.Cu" signal "BOTTOM")
		(9 "F.Adhes" user "F.Adhesive")
		(11 "B.Adhes" user "B.Adhesive")
		(13 "F.Paste" user "Package Geometry/Pastemask Top")
		(15 "B.Paste" user "Package Geometry/Pastemask Bottom")
		(5 "F.SilkS" user "Ref Des/Silkscreen Top")
		(7 "B.SilkS" user "Ref Des/Silkscreen Bottom")
		(1 "F.Mask" user "Board Geometry/Soldermask Top")
		(3 "B.Mask" user "Board Geometry/Soldermask Bottom")
		(17 "Dwgs.User" user "User.Drawings")
		(19 "Cmts.User" user "User.Comments")
		(21 "Eco1.User" user "User.Eco1")
		(23 "Eco2.User" user "User.Eco2")
		(25 "Edge.Cuts" user "Board Geometry/Outline")
		(27 "Margin" user)
		(31 "F.CrtYd" user "Package Geometry/Place Bound Top")
		(29 "B.CrtYd" user "Package Geometry/Place Bound Bottom")
		(35 "F.Fab" user "Ref Des/Assembly Top")
		(33 "B.Fab" user "Ref Des/Assembly Bottom")
	)
	(footprint ""
		(layer "F.Cu")
		(at 278.3332 -79.6036 180)
		(property "Reference" "C6D3"
			(at 0 0 180)
			(layer "F.SilkS")
			(hide yes)
			(effects
				(font
					(size 1.27 1.27)
				)
			)
		)
		(property "Value" ""
			(at 0 0 180)
			(layer "F.Fab")
			(effects
				(font
					(size 1.27 1.27)
				)
			)
		)
		(duplicate_pad_numbers_are_jumpers no)
		(fp_poly
			(pts
				(xy -0.4953 -0.2032) (xy 0.4953 -0.2032) (xy 0.4953 1.6002) (xy -0.4953 1.6002)
			)
			(stroke
				(width 0)
				(type default)
			)
			(fill no)
			(layer "F.CrtYd")
		)
		(fp_line
			(start 0.4953 1.6002)
			(end -0.4953 1.6002)
			(stroke
				(width 0.1)
				(type default)
			)
			(layer "F.Fab")
		)
		(fp_line
			(start 0.4953 -0.2032)
			(end 0.4953 1.6002)
			(stroke
				(width 0.1)
				(type default)
			)
			(layer "F.Fab")
		)
		(fp_line
			(start -0.4953 1.6002)
			(end -0.4953 -0.2032)
			(stroke
				(width 0.1)
				(type default)
			)
			(layer "F.Fab")
		)
		(fp_line
			(start -0.4953 -0.2032)
			(end 0.4953 -0.2032)
			(stroke
				(width 0.1)
				(type default)
			)
			(layer "F.Fab")
		)
		(pad "1" smd rect
			(at 0 0 180)
			(size 0.762 0.889)
			(layers "F.Cu" "F.Mask" "F.Paste")
			(net "PVCCIO_CPU0")
		)
		(pad "2" smd rect
			(at 0 1.397 180)
			(size 0.762 0.889)
			(layers "F.Cu" "F.Mask" "F.Paste")
			(net "GND")
		)
		(zone
			(layer "F.Cu")
			(hatch none 0.5)
			(connect_pads
				(clearance 0)
			)
			(min_thickness 0.25)
			(keepout
				(tracks not_allowed)
				(vias allowed)
				(pads allowed)
				(copperpour not_allowed)
				(footprints allowed)
			)
			(placement
				(enabled no)
				(sheetname "")
			)
			(fill
				(thermal_gap 0.5)
				(thermal_bridge_width 0.5)
				(island_removal_mode 0)
			)
			(polygon
				(pts
					(xy 278.7142 -80.0481) (xy 277.9522 -80.0481) (xy 277.9522 -80.5561) (xy 278.7142 -80.5561)
				)
			)
		)
	)
	(footprint ""
		(layer "F.Cu")
		(at 322.7324 -34.163 -90)
		(property "Reference" "R6F5"
			(at 0 0 270)
			(layer "F.SilkS")
			(hide yes)
			(effects
				(font
					(size 1.27 1.27)
				)
			)
		)
		(property "Value" ""
			(at 0 0 270)
			(layer "F.Fab")
			(effects
				(font
					(size 1.27 1.27)
				)
			)
		)
		(duplicate_pad_numbers_are_jumpers no)
		(fp_poly
			(pts
				(xy -0.2794 -0.1016) (xy 0.2794 -0.1016) (xy 0.2794 0.9906) (xy -0.2794 0.9906)
			)
			(stroke
				(width 0)
				(type default)
			)
			(fill no)
			(layer "F.CrtYd")
		)
		(fp_line
			(start -0.2794 0.9906)
			(end 0.2794 0.9906)
			(stroke
				(width 0.1)
				(type default)
			)
			(layer "F.Fab")
		)
		(fp_line
			(start 0.2794 0.9906)
			(end 0.2794 -0.1016)
			(stroke
				(width 0.1)
				(type default)
			)
			(layer "F.Fab")
		)
		(fp_line
			(start -0.2794 -0.1016)
			(end -0.2794 0.9906)
			(stroke
				(width 0.1)
				(type default)
			)
			(layer "F.Fab")
		)
		(fp_line
			(start 0.2794 -0.1016)
			(end -0.2794 -0.1016)
			(stroke
				(width 0.1)
				(type default)
			)
			(layer "F.Fab")
		)
		(pad "1" smd rect
			(at 0 0 270)
			(size 0.508 0.508)
			(layers "F.Cu" "F.Mask" "F.Paste")
			(net "FM_ADR_COMPLETE_CPU1_N")
		)
		(pad "2" smd rect
			(at 0 0.889 270)
			(size 0.508 0.508)
			(layers "F.Cu" "F.Mask" "F.Paste")
			(net "FM_ADR_COMPLETE_GHJ_N")
		)
		(zone
			(layer "F.Cu")
			(hatch none 0.5)
			(connect_pads
				(clearance 0)
			)
			(min_thickness 0.25)
			(keepout
				(tracks not_allowed)
				(vias allowed)
				(pads allowed)
				(copperpour not_allowed)
				(footprints allowed)
			)
			(placement
				(enabled no)
				(sheetname "")
			)
			(fill
				(thermal_gap 0.5)
				(thermal_bridge_width 0.5)
				(island_removal_mode 0)
			)
			(polygon
				(pts
					(xy 322.0974 -34.417) (xy 322.0974 -33.909) (xy 322.4784 -33.909) (xy 322.4784 -34.417)
				)
			)
		)
		(zone
			(layer "F.Cu")
			(hatch none 0.5)
			(connect_pads
				(clearance 0)
			)
			(min_thickness 0.25)
			(keepout
				(tracks allowed)
				(vias not_allowed)
				(pads allowed)
				(copperpour not_allowed)
				(footprints allowed)
			)
			(placement
				(enabled no)
				(sheetname "")
			)
			(fill
				(thermal_gap 0.5)
				(thermal_bridge_width 0.5)
				(island_removal_mode 0)
			)
			(polygon
				(pts
					(xy 322.4784 -34.417) (xy 322.4784 -33.909) (xy 322.0974 -33.909) (xy 322.0974 -34.417)
				)
			)
		)
	)
)
